(kicad_pcb
	(version 20260206)
	(generator "pcbnew")
	(generator_version "10.0")
	(general
		(thickness 1.6)
		(legacy_teardrops no)
	)
	(paper "A4")
	(title_block
		(title "03242023_DA0F0TMBIJ0_F0T_Motherboard_J_brd_V01_OCP.brd")
		(comment 1 "Grand Teton / footprints 5073-5079 of 6105")
	)
	(layers
		(0 "F.Cu" signal "TOP")
		(4 "In1.Cu" signal "GND")
		(6 "In2.Cu" signal "IN1")
		(8 "In3.Cu" signal "GND1")
		(10 "In4.Cu" signal "IN2")
		(12 "In5.Cu" signal "GND2")
		(14 "In6.Cu" signal "IN3")
		(16 "In7.Cu" signal "GND3")
		(18 "In8.Cu" signal "VCC")
		(20 "In9.Cu" signal "VCC1")
		(22 "In10.Cu" signal "GND4")
		(24 "In11.Cu" signal "IN4")
		(26 "In12.Cu" signal "GND5")
		(28 "In13.Cu" signal "IN5")
		(30 "In14.Cu" signal "GND6")
		(32 "In15.Cu" signal "IN6")
		(34 "In16.Cu" signal "GND7")
		(2 "B.Cu" signal "BOTTOM")
		(9 "F.Adhes" user "F.Adhesive")
		(11 "B.Adhes" user "B.Adhesive")
		(13 "F.Paste" user "Package Geometry/Pastemask Top")
		(15 "B.Paste" user "Package Geometry/Pastemask Bottom")
		(5 "F.SilkS" user "Ref Des/Silkscreen Top")
		(7 "B.SilkS" user "Ref Des/Silkscreen Bottom")
		(1 "F.Mask" user "Board Geometry/Soldermask Top")
		(3 "B.Mask" user "Board Geometry/Soldermask Bottom")
		(17 "Dwgs.User" user "User.Drawings")
		(19 "Cmts.User" user "User.Comments")
		(21 "Eco1.User" user "User.Eco1")
		(23 "Eco2.User" user "User.Eco2")
		(25 "Edge.Cuts" user "Board Geometry/Outline")
		(27 "Margin" user)
		(31 "F.CrtYd" user "Package Geometry/Place Bound Top")
		(29 "B.CrtYd" user "Package Geometry/Place Bound Bottom")
		(35 "F.Fab" user "Ref Des/Assembly Top")
		(33 "B.Fab" user "Ref Des/Assembly Bottom")
	)
	(footprint ""
		(layer "B.Cu")
		(at 307.984398 -190.45047 90)
		(property "Reference" "R556"
			(at 0 0 90)
			(layer "B.SilkS")
			(hide yes)
			(effects
				(font
					(size 1.27 1.27)
				)
				(justify mirror)
			)
		)
		(property "Value" ""
			(at 0 0 90)
			(layer "B.Fab")
			(effects
				(font
					(size 1.27 1.27)
				)
				(justify mirror)
			)
		)
		(duplicate_pad_numbers_are_jumpers no)
		(fp_line
			(start 0.7874 -0.4064)
			(end -0.7874 -0.4064)
			(stroke
				(width 0.1524)
				(type default)
			)
			(layer "B.SilkS")
		)
		(fp_line
			(start -0.7874 -0.4064)
			(end -0.7874 0.4064)
			(stroke
				(width 0.1524)
				(type default)
			)
			(layer "B.SilkS")
		)
		(fp_line
			(start 0.7874 0.4064)
			(end 0.7874 -0.4064)
			(stroke
				(width 0.1524)
				(type default)
			)
			(layer "B.SilkS")
		)
		(fp_line
			(start -0.7874 0.4064)
			(end 0.7874 0.4064)
			(stroke
				(width 0.1524)
				(type default)
			)
			(layer "B.SilkS")
		)
		(fp_line
			(start 0.67945 -0.305054)
			(end 0.12065 -0.305054)
			(stroke
				(width 0.1)
				(type default)
			)
			(layer "B.Fab")
		)
		(fp_line
			(start 0.12065 -0.305054)
			(end 0.12065 -0.2794)
			(stroke
				(width 0.1)
				(type default)
			)
			(layer "B.Fab")
		)
		(fp_line
			(start -0.12065 -0.3048)
			(end -0.67945 -0.3048)
			(stroke
				(width 0.1)
				(type default)
			)
			(layer "B.Fab")
		)
		(fp_line
			(start -0.67945 -0.3048)
			(end -0.67945 0.3048)
			(stroke
				(width 0.1)
				(type default)
			)
			(layer "B.Fab")
		)
		(fp_line
			(start 0.12065 -0.2794)
			(end -0.12065 -0.2794)
			(stroke
				(width 0.1)
				(type default)
			)
			(layer "B.Fab")
		)
		(fp_line
			(start -0.12065 -0.2794)
			(end -0.12065 -0.3048)
			(stroke
				(width 0.1)
				(type default)
			)
			(layer "B.Fab")
		)
		(fp_line
			(start 0.12065 0.2794)
			(end 0.12065 0.3048)
			(stroke
				(width 0.1)
				(type default)
			)
			(layer "B.Fab")
		)
		(fp_line
			(start -0.120396 0.2794)
			(end 0.12065 0.2794)
			(stroke
				(width 0.1)
				(type default)
			)
			(layer "B.Fab")
		)
		(fp_line
			(start 0.67945 0.3048)
			(end 0.67945 -0.305054)
			(stroke
				(width 0.1)
				(type default)
			)
			(layer "B.Fab")
		)
		(fp_line
			(start 0.12065 0.3048)
			(end 0.67945 0.3048)
			(stroke
				(width 0.1)
				(type default)
			)
			(layer "B.Fab")
		)
		(fp_line
			(start -0.120396 0.3048)
			(end -0.120396 0.2794)
			(stroke
				(width 0.1)
				(type default)
			)
			(layer "B.Fab")
		)
		(fp_line
			(start -0.67945 0.3048)
			(end -0.120396 0.3048)
			(stroke
				(width 0.1)
				(type default)
			)
			(layer "B.Fab")
		)
		(pad "1" smd circle
			(at 0.40005 0 270)
			(size 0 0)
			(layers "B.Cu" "B.Mask" "B.Paste")
			(net "SVID_ALERT1_CPU0_R_N")
		)
		(pad "2" smd circle
			(at -0.40005 0 270)
			(size 0 0)
			(layers "B.Cu" "B.Mask" "B.Paste")
			(net "PVNN_TERM_CPU0")
		)
	)
	(footprint ""
		(layer "B.Cu")
		(at 175.355758 -112.97539 180)
		(property "Reference" "C1917"
			(at 0 0 0)
			(layer "B.SilkS")
			(hide yes)
			(effects
				(font
					(size 1.27 1.27)
				)
				(justify mirror)
			)
		)
		(property "Value" ""
			(at 0 0 0)
			(layer "B.Fab")
			(effects
				(font
					(size 1.27 1.27)
				)
				(justify mirror)
			)
		)
		(duplicate_pad_numbers_are_jumpers no)
		(fp_line
			(start 0.69215 0.2921)
			(end 0.69215 -0.2921)
			(stroke
				(width 0.1524)
				(type default)
			)
			(layer "B.SilkS")
		)
		(fp_line
			(start 0.69215 -0.2921)
			(end -0.69215 -0.2921)
			(stroke
				(width 0.1524)
				(type default)
			)
			(layer "B.SilkS")
		)
		(fp_line
			(start -0.69215 0.2921)
			(end 0.69215 0.2921)
			(stroke
				(width 0.1524)
				(type default)
			)
			(layer "B.SilkS")
		)
		(fp_line
			(start -0.69215 -0.2921)
			(end -0.69215 0.2921)
			(stroke
				(width 0.1524)
				(type default)
			)
			(layer "B.SilkS")
		)
		(fp_line
			(start 0.51435 0.2794)
			(end 0.51435 -0.2794)
			(stroke
				(width 0.1)
				(type default)
			)
			(layer "B.Fab")
		)
		(fp_line
			(start 0.51435 -0.2794)
			(end -0.51435 -0.2794)
			(stroke
				(width 0.1)
				(type default)
			)
			(layer "B.Fab")
		)
		(fp_line
			(start -0.51435 0.2794)
			(end 0.51435 0.2794)
			(stroke
				(width 0.1)
				(type default)
			)
			(layer "B.Fab")
		)
		(fp_line
			(start -0.51435 -0.2794)
			(end -0.51435 0.2794)
			(stroke
				(width 0.1)
				(type default)
			)
			(layer "B.Fab")
		)
		(pad "1" smd circle
			(at 0.40005 0)
			(size 0 0)
			(layers "B.Cu" "B.Mask" "B.Paste")
			(net "P3V3_AUX_FPGA_VCCIO0")
		)
		(pad "2" smd circle
			(at -0.40005 0)
			(size 0 0)
			(layers "B.Cu" "B.Mask" "B.Paste")
			(net "GND")
		)
		(zone
			(layer "B.Cu")
			(hatch none 0.5)
			(connect_pads
				(clearance 0)
			)
			(min_thickness 0.25)
			(keepout
				(tracks not_allowed)
				(vias allowed)
				(pads allowed)
				(copperpour not_allowed)
				(footprints allowed)
			)
			(placement
				(enabled no)
				(sheetname "")
			)
			(fill
				(thermal_gap 0.5)
				(thermal_bridge_width 0.5)
				(island_removal_mode 0)
			)
			(polygon
				(pts
					(xy 175.165258 -113.06302) (xy 175.256698 -113.121186) (xy 175.456088 -113.121186) (xy 175.546258 -113.06302)
					(xy 175.546258 -112.88776) (xy 175.456088 -112.82934) (xy 175.256698 -112.82934) (xy 175.165258 -112.887506)
				)
			)
		)
	)
	(footprint ""
		(layer "B.Cu")
		(at 263.637014 -321.549776 -90)
		(property "Reference" "C25"
			(at 0 0 90)
			(layer "B.SilkS")
			(hide yes)
			(effects
				(font
					(size 1.27 1.27)
				)
				(justify mirror)
			)
		)
		(property "Value" ""
			(at 0 0 90)
			(layer "B.Fab")
			(effects
				(font
					(size 1.27 1.27)
				)
				(justify mirror)
			)
		)
		(duplicate_pad_numbers_are_jumpers no)
		(fp_line
			(start -1.524 0.762)
			(end 1.524 0.762)
			(stroke
				(width 0.1524)
				(type default)
			)
			(layer "B.SilkS")
		)
		(fp_line
			(start 1.524 0.762)
			(end 1.524 -0.762)
			(stroke
				(width 0.1524)
				(type default)
			)
			(layer "B.SilkS")
		)
		(fp_line
			(start -1.524 -0.762)
			(end -1.524 0.762)
			(stroke
				(width 0.1524)
				(type default)
			)
			(layer "B.SilkS")
		)
		(fp_line
			(start 1.524 -0.762)
			(end -1.524 -0.762)
			(stroke
				(width 0.1524)
				(type default)
			)
			(layer "B.SilkS")
		)
		(fp_line
			(start -1.1049 0.724916)
			(end -1.1049 -0.724916)
			(stroke
				(width 0.1)
				(type default)
			)
			(layer "B.Fab")
		)
		(fp_line
			(start 1.1049 0.724916)
			(end -1.1049 0.724916)
			(stroke
				(width 0.1)
				(type default)
			)
			(layer "B.Fab")
		)
		(fp_line
			(start -1.1049 -0.724916)
			(end 1.1049 -0.724916)
			(stroke
				(width 0.1)
				(type default)
			)
			(layer "B.Fab")
		)
		(fp_line
			(start 1.1049 -0.724916)
			(end 1.1049 0.724916)
			(stroke
				(width 0.1)
				(type default)
			)
			(layer "B.Fab")
		)
		(pad "1" smd rect
			(at 0.889 0 270)
			(size 1.016 1.27)
			(layers "B.Cu" "B.Mask" "B.Paste")
			(net "P12V_S3_AUX_CPU0_NVDIMM")
		)
		(pad "2" smd rect
			(at -0.889 0 270)
			(size 1.016 1.27)
			(layers "B.Cu" "B.Mask" "B.Paste")
			(net "GND")
		)
	)
	(footprint ""
		(layer "B.Cu")
		(at 185.755788 -116.975382 180)
		(property "Reference" "C1894"
			(at 0 0 0)
			(layer "B.SilkS")
			(hide yes)
			(effects
				(font
					(size 1.27 1.27)
				)
				(justify mirror)
			)
		)
		(property "Value" ""
			(at 0 0 0)
			(layer "B.Fab")
			(effects
				(font
					(size 1.27 1.27)
				)
				(justify mirror)
			)
		)
		(duplicate_pad_numbers_are_jumpers no)
		(fp_line
			(start 0.69215 0.2921)
			(end 0.69215 -0.2921)
			(stroke
				(width 0.1524)
				(type default)
			)
			(layer "B.SilkS")
		)
		(fp_line
			(start 0.69215 -0.2921)
			(end -0.69215 -0.2921)
			(stroke
				(width 0.1524)
				(type default)
			)
			(layer "B.SilkS")
		)
		(fp_line
			(start -0.69215 0.2921)
			(end 0.69215 0.2921)
			(stroke
				(width 0.1524)
				(type default)
			)
			(layer "B.SilkS")
		)
		(fp_line
			(start -0.69215 -0.2921)
			(end -0.69215 0.2921)
			(stroke
				(width 0.1524)
				(type default)
			)
			(layer "B.SilkS")
		)
		(fp_line
			(start 0.51435 0.2794)
			(end 0.51435 -0.2794)
			(stroke
				(width 0.1)
				(type default)
			)
			(layer "B.Fab")
		)
		(fp_line
			(start 0.51435 -0.2794)
			(end -0.51435 -0.2794)
			(stroke
				(width 0.1)
				(type default)
			)
			(layer "B.Fab")
		)
		(fp_line
			(start -0.51435 0.2794)
			(end 0.51435 0.2794)
			(stroke
				(width 0.1)
				(type default)
			)
			(layer "B.Fab")
		)
		(fp_line
			(start -0.51435 -0.2794)
			(end -0.51435 0.2794)
			(stroke
				(width 0.1)
				(type default)
			)
			(layer "B.Fab")
		)
		(pad "1" smd circle
			(at 0.40005 0)
			(size 0 0)
			(layers "B.Cu" "B.Mask" "B.Paste")
			(net "P3V3_AUX_FPGA_VCCIO2")
		)
		(pad "2" smd circle
			(at -0.40005 0)
			(size 0 0)
			(layers "B.Cu" "B.Mask" "B.Paste")
			(net "GND")
		)
		(zone
			(layer "B.Cu")
			(hatch none 0.5)
			(connect_pads
				(clearance 0)
			)
			(min_thickness 0.25)
			(keepout
				(tracks not_allowed)
				(vias allowed)
				(pads allowed)
				(copperpour not_allowed)
				(footprints allowed)
			)
			(placement
				(enabled no)
				(sheetname "")
			)
			(fill
				(thermal_gap 0.5)
				(thermal_bridge_width 0.5)
				(island_removal_mode 0)
			)
			(polygon
				(pts
					(xy 185.565288 -117.063012) (xy 185.656728 -117.121178) (xy 185.856118 -117.121178) (xy 185.946288 -117.063012)
					(xy 185.946288 -116.887752) (xy 185.856118 -116.829332) (xy 185.656728 -116.829332) (xy 185.565288 -116.887498)
				)
			)
		)
	)
	(footprint ""
		(layer "B.Cu")
		(at 371.665246 -354.93833 90)
		(property "Reference" "C1300"
			(at 0 0 90)
			(layer "B.SilkS")
			(hide yes)
			(effects
				(font
					(size 1.27 1.27)
				)
				(justify mirror)
			)
		)
		(property "Value" ""
			(at 0 0 90)
			(layer "B.Fab")
			(effects
				(font
					(size 1.27 1.27)
				)
				(justify mirror)
			)
		)
		(duplicate_pad_numbers_are_jumpers no)
		(fp_line
			(start 0.7874 -0.4064)
			(end -0.7874 -0.4064)
			(stroke
				(width 0.1524)
				(type default)
			)
			(layer "B.SilkS")
		)
		(fp_line
			(start -0.7874 -0.4064)
			(end -0.7874 0.4064)
			(stroke
				(width 0.1524)
				(type default)
			)
			(layer "B.SilkS")
		)
		(fp_line
			(start 0.7874 0.4064)
			(end 0.7874 -0.4064)
			(stroke
				(width 0.1524)
				(type default)
			)
			(layer "B.SilkS")
		)
		(fp_line
			(start -0.7874 0.4064)
			(end 0.7874 0.4064)
			(stroke
				(width 0.1524)
				(type default)
			)
			(layer "B.SilkS")
		)
		(fp_line
			(start 0.67945 -0.305054)
			(end 0.12065 -0.305054)
			(stroke
				(width 0.1)
				(type default)
			)
			(layer "B.Fab")
		)
		(fp_line
			(start 0.12065 -0.305054)
			(end 0.12065 -0.2794)
			(stroke
				(width 0.1)
				(type default)
			)
			(layer "B.Fab")
		)
		(fp_line
			(start -0.12065 -0.3048)
			(end -0.67945 -0.3048)
			(stroke
				(width 0.1)
				(type default)
			)
			(layer "B.Fab")
		)
		(fp_line
			(start -0.67945 -0.3048)
			(end -0.67945 0.3048)
			(stroke
				(width 0.1)
				(type default)
			)
			(layer "B.Fab")
		)
		(fp_line
			(start 0.12065 -0.2794)
			(end -0.12065 -0.2794)
			(stroke
				(width 0.1)
				(type default)
			)
			(layer "B.Fab")
		)
		(fp_line
			(start -0.12065 -0.2794)
			(end -0.12065 -0.3048)
			(stroke
				(width 0.1)
				(type default)
			)
			(layer "B.Fab")
		)
		(fp_line
			(start 0.12065 0.2794)
			(end 0.12065 0.3048)
			(stroke
				(width 0.1)
				(type default)
			)
			(layer "B.Fab")
		)
		(fp_line
			(start -0.120396 0.2794)
			(end 0.12065 0.2794)
			(stroke
				(width 0.1)
				(type default)
			)
			(layer "B.Fab")
		)
		(fp_line
			(start 0.67945 0.3048)
			(end 0.67945 -0.305054)
			(stroke
				(width 0.1)
				(type default)
			)
			(layer "B.Fab")
		)
		(fp_line
			(start 0.12065 0.3048)
			(end 0.67945 0.3048)
			(stroke
				(width 0.1)
				(type default)
			)
			(layer "B.Fab")
		)
		(fp_line
			(start -0.120396 0.3048)
			(end -0.120396 0.2794)
			(stroke
				(width 0.1)
				(type default)
			)
			(layer "B.Fab")
		)
		(fp_line
			(start -0.67945 0.3048)
			(end -0.120396 0.3048)
			(stroke
				(width 0.1)
				(type default)
			)
			(layer "B.Fab")
		)
		(pad "1" smd circle
			(at 0.40005 0 270)
			(size 0 0)
			(layers "B.Cu" "B.Mask" "B.Paste")
			(net "FM_PVPP_HBM_CPU0_EN")
		)
		(pad "2" smd circle
			(at -0.40005 0 270)
			(size 0 0)
			(layers "B.Cu" "B.Mask" "B.Paste")
			(net "GND")
		)
	)
	(footprint ""
		(layer "B.Cu")
		(at 52.730908 -193.25971 -90)
		(property "Reference" "R1394"
			(at 0 0 90)
			(layer "B.SilkS")
			(hide yes)
			(effects
				(font
					(size 1.27 1.27)
				)
				(justify mirror)
			)
		)
		(property "Value" ""
			(at 0 0 90)
			(layer "B.Fab")
			(effects
				(font
					(size 1.27 1.27)
				)
				(justify mirror)
			)
		)
		(duplicate_pad_numbers_are_jumpers no)
		(fp_line
			(start -0.7874 0.4064)
			(end 0.7874 0.4064)
			(stroke
				(width 0.1524)
				(type default)
			)
			(layer "B.SilkS")
		)
		(fp_line
			(start 0.7874 0.4064)
			(end 0.7874 -0.4064)
			(stroke
				(width 0.1524)
				(type default)
			)
			(layer "B.SilkS")
		)
		(fp_line
			(start -0.7874 -0.4064)
			(end -0.7874 0.4064)
			(stroke
				(width 0.1524)
				(type default)
			)
			(layer "B.SilkS")
		)
		(fp_line
			(start 0.7874 -0.4064)
			(end -0.7874 -0.4064)
			(stroke
				(width 0.1524)
				(type default)
			)
			(layer "B.SilkS")
		)
		(fp_line
			(start -0.67945 0.3048)
			(end -0.120396 0.3048)
			(stroke
				(width 0.1)
				(type default)
			)
			(layer "B.Fab")
		)
		(fp_line
			(start -0.120396 0.3048)
			(end -0.120396 0.2794)
			(stroke
				(width 0.1)
				(type default)
			)
			(layer "B.Fab")
		)
		(fp_line
			(start 0.12065 0.3048)
			(end 0.67945 0.3048)
			(stroke
				(width 0.1)
				(type default)
			)
			(layer "B.Fab")
		)
		(fp_line
			(start 0.67945 0.3048)
			(end 0.67945 -0.305054)
			(stroke
				(width 0.1)
				(type default)
			)
			(layer "B.Fab")
		)
		(fp_line
			(start -0.120396 0.2794)
			(end 0.12065 0.2794)
			(stroke
				(width 0.1)
				(type default)
			)
			(layer "B.Fab")
		)
		(fp_line
			(start 0.12065 0.2794)
			(end 0.12065 0.3048)
			(stroke
				(width 0.1)
				(type default)
			)
			(layer "B.Fab")
		)
		(fp_line
			(start -0.12065 -0.2794)
			(end -0.12065 -0.3048)
			(stroke
				(width 0.1)
				(type default)
			)
			(layer "B.Fab")
		)
		(fp_line
			(start 0.12065 -0.2794)
			(end -0.12065 -0.2794)
			(stroke
				(width 0.1)
				(type default)
			)
			(layer "B.Fab")
		)
		(fp_line
			(start -0.67945 -0.3048)
			(end -0.67945 0.3048)
			(stroke
				(width 0.1)
				(type default)
			)
			(layer "B.Fab")
		)
		(fp_line
			(start -0.12065 -0.3048)
			(end -0.67945 -0.3048)
			(stroke
				(width 0.1)
				(type default)
			)
			(layer "B.Fab")
		)
		(fp_line
			(start 0.12065 -0.305054)
			(end 0.12065 -0.2794)
			(stroke
				(width 0.1)
				(type default)
			)
			(layer "B.Fab")
		)
		(fp_line
			(start 0.67945 -0.305054)
			(end 0.12065 -0.305054)
			(stroke
				(width 0.1)
				(type default)
			)
			(layer "B.Fab")
		)
		(pad "1" smd circle
			(at 0.40005 0 90)
			(size 0 0)
			(layers "B.Cu" "B.Mask" "B.Paste")
			(net "GND")
		)
		(pad "2" smd circle
			(at -0.40005 0 90)
			(size 0 0)
			(layers "B.Cu" "B.Mask" "B.Paste")
			(net "FM_S3M_CPU1_LVC1_GPIO_3")
		)
	)
	(footprint ""
		(layer "B.Cu")
		(at 178.26482 -356.41153 -90)
		(property "Reference" "PR1333"
			(at 0 0 90)
			(layer "B.SilkS")
			(hide yes)
			(effects
				(font
					(size 1.27 1.27)
				)
				(justify mirror)
			)
		)
		(property "Value" ""
			(at 0 0 90)
			(layer "B.Fab")
			(effects
				(font
					(size 1.27 1.27)
				)
				(justify mirror)
			)
		)
		(duplicate_pad_numbers_are_jumpers no)
		(fp_line
			(start -0.7874 0.4064)
			(end 0.7874 0.4064)
			(stroke
				(width 0.1524)
				(type default)
			)
			(layer "B.SilkS")
		)
		(fp_line
			(start 0.7874 0.4064)
			(end 0.7874 -0.4064)
			(stroke
				(width 0.1524)
				(type default)
			)
			(layer "B.SilkS")
		)
		(fp_line
			(start -0.7874 -0.4064)
			(end -0.7874 0.4064)
			(stroke
				(width 0.1524)
				(type default)
			)
			(layer "B.SilkS")
		)
		(fp_line
			(start 0.7874 -0.4064)
			(end -0.7874 -0.4064)
			(stroke
				(width 0.1524)
				(type default)
			)
			(layer "B.SilkS")
		)
		(fp_line
			(start -0.67945 0.3048)
			(end -0.120396 0.3048)
			(stroke
				(width 0.1)
				(type default)
			)
			(layer "B.Fab")
		)
		(fp_line
			(start -0.120396 0.3048)
			(end -0.120396 0.2794)
			(stroke
				(width 0.1)
				(type default)
			)
			(layer "B.Fab")
		)
		(fp_line
			(start 0.12065 0.3048)
			(end 0.67945 0.3048)
			(stroke
				(width 0.1)
				(type default)
			)
			(layer "B.Fab")
		)
		(fp_line
			(start 0.67945 0.3048)
			(end 0.67945 -0.305054)
			(stroke
				(width 0.1)
				(type default)
			)
			(layer "B.Fab")
		)
		(fp_line
			(start -0.120396 0.2794)
			(end 0.12065 0.2794)
			(stroke
				(width 0.1)
				(type default)
			)
			(layer "B.Fab")
		)
		(fp_line
			(start 0.12065 0.2794)
			(end 0.12065 0.3048)
			(stroke
				(width 0.1)
				(type default)
			)
			(layer "B.Fab")
		)
		(fp_line
			(start -0.12065 -0.2794)
			(end -0.12065 -0.3048)
			(stroke
				(width 0.1)
				(type default)
			)
			(layer "B.Fab")
		)
		(fp_line
			(start 0.12065 -0.2794)
			(end -0.12065 -0.2794)
			(stroke
				(width 0.1)
				(type default)
			)
			(layer "B.Fab")
		)
		(fp_line
			(start -0.67945 -0.3048)
			(end -0.67945 0.3048)
			(stroke
				(width 0.1)
				(type default)
			)
			(layer "B.Fab")
		)
		(fp_line
			(start -0.12065 -0.3048)
			(end -0.67945 -0.3048)
			(stroke
				(width 0.1)
				(type default)
			)
			(layer "B.Fab")
		)
		(fp_line
			(start 0.12065 -0.305054)
			(end 0.12065 -0.2794)
			(stroke
				(width 0.1)
				(type default)
			)
			(layer "B.Fab")
		)
		(fp_line
			(start 0.67945 -0.305054)
			(end 0.12065 -0.305054)
			(stroke
				(width 0.1)
				(type default)
			)
			(layer "B.Fab")
		)
		(pad "1" smd circle
			(at 0.40005 0 90)
			(size 0 0)
			(layers "B.Cu" "B.Mask" "B.Paste")
			(net "PVCCFA_EHV_FIVRA_CPU1_VOS3")
		)
		(pad "2" smd circle
			(at -0.40005 0 90)
			(size 0 0)
			(layers "B.Cu" "B.Mask" "B.Paste")
			(net "PVCCFA_EHV_FIVRA_CPU1")
		)
	)
)
